(kicad_pcb
	(version 20260206)
	(generator "pcbnew")
	(generator_version "10.0")
	(general
		(thickness 1.6)
		(legacy_teardrops no)
	)
	(paper "A4")
	(title_block
		(title "12092022_DA0F0TMDCD0_F0T_Management_Board_D_brd_V3_OCP.brd")
		(comment 1 "Grand Teton / footprint 804 of 1440 (GF1), pads 117-168 of 168")
	)
	(layers
		(0 "F.Cu" signal "TOP")
		(4 "In1.Cu" signal "GND")
		(6 "In2.Cu" signal "IN1")
		(8 "In3.Cu" signal "GND1")
		(10 "In4.Cu" signal "IN2")
		(12 "In5.Cu" signal "VCC")
		(14 "In6.Cu" signal "VCC1")
		(16 "In7.Cu" signal "IN3")
		(18 "In8.Cu" signal "GND2")
		(20 "In9.Cu" signal "IN4")
		(22 "In10.Cu" signal "GND3")
		(2 "B.Cu" signal "BOTTOM")
		(9 "F.Adhes" user "F.Adhesive")
		(11 "B.Adhes" user "B.Adhesive")
		(13 "F.Paste" user "Package Geometry/Pastemask Top")
		(15 "B.Paste" user "Package Geometry/Pastemask Bottom")
		(5 "F.SilkS" user "Ref Des/Silkscreen Top")
		(7 "B.SilkS" user "Ref Des/Silkscreen Bottom")
		(1 "F.Mask" user "Board Geometry/Soldermask Top")
		(3 "B.Mask" user "Board Geometry/Soldermask Bottom")
		(17 "Dwgs.User" user "User.Drawings")
		(19 "Cmts.User" user "User.Comments")
		(21 "Eco1.User" user "User.Eco1")
		(23 "Eco2.User" user "User.Eco2")
		(25 "Edge.Cuts" user "Board Geometry/Outline")
		(27 "Margin" user)
		(31 "F.CrtYd" user "Package Geometry/Place Bound Top")
		(29 "B.CrtYd" user "Package Geometry/Place Bound Bottom")
		(35 "F.Fab" user "Ref Des/Assembly Top")
		(33 "B.Fab" user "Ref Des/Assembly Bottom")
	)
	(footprint ""
		(layer "B.Cu")
		(at 45.260006 -114.324892 180)
		(property "Reference" "GF1"
			(at 30.591506 -4.763262 0)
			(unlocked yes)
			(layer "B.SilkS")
			(effects
				(font
					(size 0.7874 0.5842)
					(thickness 0.1524)
				)
				(justify left mirror)
			)
		)
		(property "Value" ""
			(at 0 0 0)
			(layer "B.Fab")
			(effects
				(font
					(size 1.27 1.27)
				)
				(justify mirror)
			)
		)
		(duplicate_pad_numbers_are_jumpers no)
		(pad "B47" smd rect
			(at 17.115028 3.934968)
			(size 0.381 1.7272)
			(layers "B.Cu" "B.Mask" "B.Paste")
			(net "QSPI_2_PLD_IO2")
		)
		(pad "B48" smd rect
			(at 17.714976 3.934968)
			(size 0.381 1.7272)
			(layers "B.Cu" "B.Mask" "B.Paste")
			(net "QSPI_2_PLD_IO3")
		)
		(pad "B49" smd rect
			(at 18.314924 4.13512)
			(size 0.381 2.1336)
			(layers "B.Cu" "B.Mask" "B.Paste")
			(net "GND")
		)
		(pad "B50" smd rect
			(at 18.914872 3.934968)
			(size 0.381 1.7272)
			(layers "B.Cu" "B.Mask" "B.Paste")
			(net "USB_HOST_BMC_B_DP")
		)
		(pad "B51" smd rect
			(at 19.515074 3.934968)
			(size 0.381 1.7272)
			(layers "B.Cu" "B.Mask" "B.Paste")
			(net "USB_HOST_BMC_B_DN")
		)
		(pad "B52" smd rect
			(at 20.115022 4.13512)
			(size 0.381 2.1336)
			(layers "B.Cu" "B.Mask" "B.Paste")
			(net "GND")
		)
		(pad "B53" smd rect
			(at 20.71497 3.934968)
			(size 0.381 1.7272)
			(layers "B.Cu" "B.Mask" "B.Paste")
			(net "USB_HOST_BMC_A_DP")
		)
		(pad "B54" smd rect
			(at 21.314918 3.934968)
			(size 0.381 1.7272)
			(layers "B.Cu" "B.Mask" "B.Paste")
			(net "USB_HOST_BMC_A_DN")
		)
		(pad "B55" smd rect
			(at 21.91512 4.13512)
			(size 0.381 2.1336)
			(layers "B.Cu" "B.Mask" "B.Paste")
			(net "GND")
		)
		(pad "B56" smd rect
			(at 22.515068 3.934968)
			(size 0.381 1.7272)
			(layers "B.Cu" "B.Mask" "B.Paste")
			(net "USB_FPNL_DP")
		)
		(pad "B57" smd rect
			(at 23.115016 3.934968)
			(size 0.381 1.7272)
			(layers "B.Cu" "B.Mask" "B.Paste")
			(net "USB_FPNL_DN")
		)
		(pad "B58" smd rect
			(at 23.714964 4.13512)
			(size 0.381 2.1336)
			(layers "B.Cu" "B.Mask" "B.Paste")
			(net "GND")
		)
		(pad "B59" smd rect
			(at 24.314912 3.934968)
			(size 0.381 1.7272)
			(layers "B.Cu" "B.Mask" "B.Paste")
			(net "USB3_FPNL_TXP")
		)
		(pad "B60" smd rect
			(at 24.915114 3.934968)
			(size 0.381 1.7272)
			(layers "B.Cu" "B.Mask" "B.Paste")
			(net "USB3_FPNL_TXN")
		)
		(pad "B61" smd rect
			(at 25.515062 4.13512)
			(size 0.381 2.1336)
			(layers "B.Cu" "B.Mask" "B.Paste")
			(net "GND")
		)
		(pad "B62" smd rect
			(at 26.11501 3.934968)
			(size 0.381 1.7272)
			(layers "B.Cu" "B.Mask" "B.Paste")
			(net "TP_GF_B62")
		)
		(pad "B63" smd rect
			(at 26.714958 3.934968)
			(size 0.381 1.7272)
			(layers "B.Cu" "B.Mask" "B.Paste")
			(net "TP_GF_B63")
		)
		(pad "B64" smd rect
			(at 27.314906 4.13512)
			(size 0.381 2.1336)
			(layers "B.Cu" "B.Mask" "B.Paste")
			(net "GND")
		)
		(pad "B65" smd rect
			(at 27.915108 3.934968)
			(size 0.381 1.7272)
			(layers "B.Cu" "B.Mask" "B.Paste")
			(net "P2E_GPU_TX_C_DP")
		)
		(pad "B66" smd rect
			(at 28.515056 3.934968)
			(size 0.381 1.7272)
			(layers "B.Cu" "B.Mask" "B.Paste")
			(net "P2E_GPU_TX_C_DN")
		)
		(pad "B67" smd rect
			(at 29.115004 4.13512)
			(size 0.381 2.1336)
			(layers "B.Cu" "B.Mask" "B.Paste")
			(net "GND")
		)
		(pad "B68" smd rect
			(at 29.714952 3.934968)
			(size 0.381 1.7272)
			(layers "B.Cu" "B.Mask" "B.Paste")
			(net "HDD_LED_R_N")
		)
		(pad "B69" smd rect
			(at 30.3149 3.934968)
			(size 0.381 1.7272)
			(layers "B.Cu" "B.Mask" "B.Paste")
			(net "PCH_BEEP_R_LED")
		)
		(pad "B70" smd rect
			(at 30.915102 4.13512)
			(size 0.381 2.1336)
			(layers "B.Cu" "B.Mask" "B.Paste")
			(net "GND")
		)
		(pad "OA1" smd rect
			(at -30.39999 4.13512)
			(size 0.381 2.1336)
			(layers "B.Cu" "B.Mask" "B.Paste")
			(net "P12V_AUX")
		)
		(pad "OA2" smd rect
			(at -29.800042 3.934968)
			(size 0.381 1.7272)
			(layers "B.Cu" "B.Mask" "B.Paste")
			(net "P12V_AUX")
		)
		(pad "OA3" smd rect
			(at -29.200094 4.13512)
			(size 0.381 2.1336)
			(layers "B.Cu" "B.Mask" "B.Paste")
			(net "GND")
		)
		(pad "OA4" smd rect
			(at -28.599892 4.13512)
			(size 0.381 2.1336)
			(layers "B.Cu" "B.Mask" "B.Paste")
			(net "GND")
		)
		(pad "OA5" smd rect
			(at -27.999944 4.13512)
			(size 0.381 2.1336)
			(layers "B.Cu" "B.Mask" "B.Paste")
			(net "I3C1_SPD_SCL")
		)
		(pad "OA6" smd rect
			(at -27.399996 4.13512)
			(size 0.381 2.1336)
			(layers "B.Cu" "B.Mask" "B.Paste")
			(net "I3C1_SPD_SDA")
		)
		(pad "OA7" smd rect
			(at -26.800048 4.13512)
			(size 0.381 2.1336)
			(layers "B.Cu" "B.Mask" "B.Paste")
			(net "I3C2_SPD_SCL")
		)
		(pad "OA8" smd rect
			(at -26.2001 4.13512)
			(size 0.381 2.1336)
			(layers "B.Cu" "B.Mask" "B.Paste")
			(net "I3C2_SPD_SDA")
		)
		(pad "OA9" smd rect
			(at -25.599898 4.13512)
			(size 0.381 2.1336)
			(layers "B.Cu" "B.Mask" "B.Paste")
			(net "I3C3_SPD_SCL")
		)
		(pad "OA10" smd rect
			(at -24.99995 4.13512)
			(size 0.381 2.1336)
			(layers "B.Cu" "B.Mask" "B.Paste")
			(net "I3C3_SPD_SDA")
		)
		(pad "OA11" smd rect
			(at -24.400002 3.934968)
			(size 0.381 1.7272)
			(layers "B.Cu" "B.Mask" "B.Paste")
			(net "I3C4_SPD_SCL")
		)
		(pad "OA12" smd rect
			(at -23.800054 3.934968)
			(size 0.381 1.7272)
			(layers "B.Cu" "B.Mask" "B.Paste")
			(net "I3C4_SPD_SDA")
		)
		(pad "OA13" smd rect
			(at -23.200106 4.13512)
			(size 0.381 2.1336)
			(layers "B.Cu" "B.Mask" "B.Paste")
			(net "GND")
		)
		(pad "OA14" smd rect
			(at -22.599904 4.13512)
			(size 0.381 2.1336)
			(layers "B.Cu" "B.Mask" "B.Paste")
			(net "FM_VIRTUAL_RESEAT")
		)
		(pad "OB1" smd rect
			(at -30.39999 4.13512)
			(size 0.381 2.1336)
			(layers "B.Cu" "B.Mask" "B.Paste")
			(net "P12V_AUX")
		)
		(pad "OB2" smd rect
			(at -29.800042 4.13512)
			(size 0.381 2.1336)
			(layers "B.Cu" "B.Mask" "B.Paste")
			(net "P12V_AUX")
		)
		(pad "OB3" smd rect
			(at -29.200094 4.13512)
			(size 0.381 2.1336)
			(layers "B.Cu" "B.Mask" "B.Paste")
			(net "FM_PRSNT_0_R_N")
		)
		(pad "OB4" smd rect
			(at -28.599892 4.13512)
			(size 0.381 2.1336)
			(layers "B.Cu" "B.Mask" "B.Paste")
			(net "GND")
		)
		(pad "OB5" smd rect
			(at -27.999944 4.13512)
			(size 0.381 2.1336)
			(layers "B.Cu" "B.Mask" "B.Paste")
			(net "UART_BIC_GF_TXD")
		)
		(pad "OB6" smd rect
			(at -27.399996 4.13512)
			(size 0.381 2.1336)
			(layers "B.Cu" "B.Mask" "B.Paste")
			(net "UART_BIC_GF_RXD")
		)
		(pad "OB7" smd rect
			(at -26.800048 4.13512)
			(size 0.381 2.1336)
			(layers "B.Cu" "B.Mask" "B.Paste")
			(net "GND")
		)
		(pad "OB8" smd rect
			(at -26.2001 4.13512)
			(size 0.381 2.1336)
			(layers "B.Cu" "B.Mask" "B.Paste")
			(net "UART_SYS_DBG_TX")
		)
		(pad "OB9" smd rect
			(at -25.599898 4.13512)
			(size 0.381 2.1336)
			(layers "B.Cu" "B.Mask" "B.Paste")
			(net "UART_SYS_DBG_RX")
		)
		(pad "OB10" smd rect
			(at -24.99995 4.13512)
			(size 0.381 2.1336)
			(layers "B.Cu" "B.Mask" "B.Paste")
			(net "GND")
		)
		(pad "OB11" smd rect
			(at -24.400002 3.934968)
			(size 0.381 1.7272)
			(layers "B.Cu" "B.Mask" "B.Paste")
			(net "RST_SRST_PLD_BMC_R_N")
		)
		(pad "OB12" smd rect
			(at -23.800054 3.934968)
			(size 0.381 1.7272)
			(layers "B.Cu" "B.Mask" "B.Paste")
			(net "SPI_TPM_CS_N")
		)
		(pad "OB13" smd rect
			(at -23.200106 4.13512)
			(size 0.381 2.1336)
			(layers "B.Cu" "B.Mask" "B.Paste")
			(net "H_CPU_CATERR_LVC2_R2_N")
		)
		(pad "OB14" smd rect
			(at -22.599904 4.13512)
			(size 0.381 2.1336)
			(layers "B.Cu" "B.Mask" "B.Paste")
			(net "FM_SOL_UART_CH_SEL")
		)
	)
)
